(kicad_pcb
	(version 20260206)
	(generator "pcbnew")
	(generator_version "10.0")
	(general
		(thickness 1.6)
		(legacy_teardrops no)
	)
	(paper "A4")
	(title_block
		(title "03242023_DA0F0TMBIJ0_F0T_Motherboard_J_brd_V01_OCP.brd")
		(comment 1 "Grand Teton / footprints 1089-1094 of 6105")
	)
	(layers
		(0 "F.Cu" signal "TOP")
		(4 "In1.Cu" signal "GND")
		(6 "In2.Cu" signal "IN1")
		(8 "In3.Cu" signal "GND1")
		(10 "In4.Cu" signal "IN2")
		(12 "In5.Cu" signal "GND2")
		(14 "In6.Cu" signal "IN3")
		(16 "In7.Cu" signal "GND3")
		(18 "In8.Cu" signal "VCC")
		(20 "In9.Cu" signal "VCC1")
		(22 "In10.Cu" signal "GND4")
		(24 "In11.Cu" signal "IN4")
		(26 "In12.Cu" signal "GND5")
		(28 "In13.Cu" signal "IN5")
		(30 "In14.Cu" signal "GND6")
		(32 "In15.Cu" signal "IN6")
		(34 "In16.Cu" signal "GND7")
		(2 "B.Cu" signal "BOTTOM")
		(9 "F.Adhes" user "F.Adhesive")
		(11 "B.Adhes" user "B.Adhesive")
		(13 "F.Paste" user "Package Geometry/Pastemask Top")
		(15 "B.Paste" user "Package Geometry/Pastemask Bottom")
		(5 "F.SilkS" user "Ref Des/Silkscreen Top")
		(7 "B.SilkS" user "Ref Des/Silkscreen Bottom")
		(1 "F.Mask" user "Board Geometry/Soldermask Top")
		(3 "B.Mask" user "Board Geometry/Soldermask Bottom")
		(17 "Dwgs.User" user "User.Drawings")
		(19 "Cmts.User" user "User.Comments")
		(21 "Eco1.User" user "User.Eco1")
		(23 "Eco2.User" user "User.Eco2")
		(25 "Edge.Cuts" user "Board Geometry/Outline")
		(27 "Margin" user)
		(31 "F.CrtYd" user "Package Geometry/Place Bound Top")
		(29 "B.CrtYd" user "Package Geometry/Place Bound Bottom")
		(35 "F.Fab" user "Ref Des/Assembly Top")
		(33 "B.Fab" user "Ref Des/Assembly Bottom")
	)
	(footprint ""
		(layer "F.Cu")
		(at 86.084918 -341.707978 -90)
		(property "Reference" "PC1360"
			(at 0 0 270)
			(layer "F.SilkS")
			(hide yes)
			(effects
				(font
					(size 1.27 1.27)
				)
			)
		)
		(property "Value" ""
			(at 0 0 270)
			(layer "F.Fab")
			(effects
				(font
					(size 1.27 1.27)
				)
			)
		)
		(duplicate_pad_numbers_are_jumpers no)
		(fp_line
			(start -0.7874 0.4064)
			(end -0.7874 -0.4064)
			(stroke
				(width 0.1524)
				(type default)
			)
			(layer "F.SilkS")
		)
		(fp_line
			(start 0.7874 0.4064)
			(end -0.7874 0.4064)
			(stroke
				(width 0.1524)
				(type default)
			)
			(layer "F.SilkS")
		)
		(fp_line
			(start -0.7874 -0.4064)
			(end 0.7874 -0.4064)
			(stroke
				(width 0.1524)
				(type default)
			)
			(layer "F.SilkS")
		)
		(fp_line
			(start 0.7874 -0.4064)
			(end 0.7874 0.4064)
			(stroke
				(width 0.1524)
				(type default)
			)
			(layer "F.SilkS")
		)
		(fp_line
			(start -0.67945 0.3048)
			(end -0.67945 -0.305054)
			(stroke
				(width 0.1)
				(type default)
			)
			(layer "F.Fab")
		)
		(fp_line
			(start -0.12065 0.3048)
			(end -0.67945 0.3048)
			(stroke
				(width 0.1)
				(type default)
			)
			(layer "F.Fab")
		)
		(fp_line
			(start 0.120396 0.3048)
			(end 0.120396 0.2794)
			(stroke
				(width 0.1)
				(type default)
			)
			(layer "F.Fab")
		)
		(fp_line
			(start 0.67945 0.3048)
			(end 0.120396 0.3048)
			(stroke
				(width 0.1)
				(type default)
			)
			(layer "F.Fab")
		)
		(fp_line
			(start -0.12065 0.2794)
			(end -0.12065 0.3048)
			(stroke
				(width 0.1)
				(type default)
			)
			(layer "F.Fab")
		)
		(fp_line
			(start 0.120396 0.2794)
			(end -0.12065 0.2794)
			(stroke
				(width 0.1)
				(type default)
			)
			(layer "F.Fab")
		)
		(fp_line
			(start -0.12065 -0.2794)
			(end 0.12065 -0.2794)
			(stroke
				(width 0.1)
				(type default)
			)
			(layer "F.Fab")
		)
		(fp_line
			(start 0.12065 -0.2794)
			(end 0.12065 -0.3048)
			(stroke
				(width 0.1)
				(type default)
			)
			(layer "F.Fab")
		)
		(fp_line
			(start 0.12065 -0.3048)
			(end 0.67945 -0.3048)
			(stroke
				(width 0.1)
				(type default)
			)
			(layer "F.Fab")
		)
		(fp_line
			(start 0.67945 -0.3048)
			(end 0.67945 0.3048)
			(stroke
				(width 0.1)
				(type default)
			)
			(layer "F.Fab")
		)
		(fp_line
			(start -0.67945 -0.305054)
			(end -0.12065 -0.305054)
			(stroke
				(width 0.1)
				(type default)
			)
			(layer "F.Fab")
		)
		(fp_line
			(start -0.12065 -0.305054)
			(end -0.12065 -0.2794)
			(stroke
				(width 0.1)
				(type default)
			)
			(layer "F.Fab")
		)
		(pad "1" smd circle
			(at -0.40005 0 270)
			(size 0 0)
			(layers "F.Cu" "F.Mask" "F.Paste")
			(net "GND")
		)
		(pad "2" smd circle
			(at 0.40005 0 270)
			(size 0 0)
			(layers "F.Cu" "F.Mask" "F.Paste")
			(net "PVCCIN_CPU1_VREF")
		)
	)
	(footprint ""
		(layer "F.Cu")
		(at 316.207648 -402.371052 -90)
		(property "Reference" "C1570"
			(at 0 0 270)
			(layer "F.SilkS")
			(hide yes)
			(effects
				(font
					(size 1.27 1.27)
				)
			)
		)
		(property "Value" ""
			(at 0 0 270)
			(layer "F.Fab")
			(effects
				(font
					(size 1.27 1.27)
				)
			)
		)
		(duplicate_pad_numbers_are_jumpers no)
		(fp_line
			(start -0.299974 0.150114)
			(end -0.299974 -0.150114)
			(stroke
				(width 0.1)
				(type default)
			)
			(layer "F.Fab")
		)
		(fp_line
			(start 0.299974 0.150114)
			(end -0.299974 0.150114)
			(stroke
				(width 0.1)
				(type default)
			)
			(layer "F.Fab")
		)
		(fp_line
			(start -0.299974 -0.150114)
			(end 0.299974 -0.150114)
			(stroke
				(width 0.1)
				(type default)
			)
			(layer "F.Fab")
		)
		(fp_line
			(start 0.299974 -0.150114)
			(end 0.299974 0.150114)
			(stroke
				(width 0.1)
				(type default)
			)
			(layer "F.Fab")
		)
		(pad "1" smd rect
			(at -0.2667 0 270)
			(size 0.3048 0.381)
			(layers "F.Cu" "F.Mask" "F.Paste")
			(net "P5E_CPU0_PE4_TX_C_DN<4>")
		)
		(pad "2" smd rect
			(at 0.2667 0 270)
			(size 0.3048 0.381)
			(layers "F.Cu" "F.Mask" "F.Paste")
			(net "P5E_CPU0_PE4_TX_DN<4>")
		)
	)
	(footprint ""
		(layer "F.Cu")
		(at 108.079286 -93.015562)
		(property "Reference" "Q81"
			(at -1.19126 1.843532 0)
			(unlocked yes)
			(layer "F.SilkS")
			(effects
				(font
					(size 0.7874 0.5842)
					(thickness 0.1524)
				)
				(justify left)
			)
		)
		(property "Value" ""
			(at 0 0 0)
			(layer "F.Fab")
			(effects
				(font
					(size 1.27 1.27)
				)
			)
		)
		(duplicate_pad_numbers_are_jumpers no)
		(fp_line
			(start -1.332738 -1.100074)
			(end -0.4826 -1.100074)
			(stroke
				(width 0.1524)
				(type default)
			)
			(layer "F.SilkS")
		)
		(fp_line
			(start -1.332738 1.100074)
			(end -1.332738 -1.100074)
			(stroke
				(width 0.1524)
				(type default)
			)
			(layer "F.SilkS")
		)
		(fp_line
			(start -0.4826 -1.100074)
			(end 0 -0.541274)
			(stroke
				(width 0.1524)
				(type default)
			)
			(layer "F.SilkS")
		)
		(fp_line
			(start 0 -0.541274)
			(end 0.4826 -1.100074)
			(stroke
				(width 0.1524)
				(type default)
			)
			(layer "F.SilkS")
		)
		(fp_line
			(start 0.4826 -1.100074)
			(end 1.332738 -1.100074)
			(stroke
				(width 0.1524)
				(type default)
			)
			(layer "F.SilkS")
		)
		(fp_line
			(start 1.332738 -1.100074)
			(end 1.332738 1.100074)
			(stroke
				(width 0.1524)
				(type default)
			)
			(layer "F.SilkS")
		)
		(fp_line
			(start 1.332738 1.100074)
			(end -1.332738 1.100074)
			(stroke
				(width 0.1524)
				(type default)
			)
			(layer "F.SilkS")
		)
		(fp_poly
			(pts
				(xy -0.649478 -1.9685) (xy -1.000506 -1.266444) (xy -1.351534 -1.9685)
			)
			(stroke
				(width 0)
				(type default)
			)
			(fill yes)
			(layer "F.SilkS")
		)
		(fp_line
			(start -0.674878 -1.100074)
			(end 0.674878 -1.100074)
			(stroke
				(width 0.1)
				(type default)
			)
			(layer "F.Fab")
		)
		(fp_line
			(start -0.674878 1.100074)
			(end -0.674878 -1.100074)
			(stroke
				(width 0.1)
				(type default)
			)
			(layer "F.Fab")
		)
		(fp_line
			(start 0.674878 -1.100074)
			(end 0.674878 1.100074)
			(stroke
				(width 0.1)
				(type default)
			)
			(layer "F.Fab")
		)
		(fp_line
			(start 0.674878 1.100074)
			(end -0.674878 1.100074)
			(stroke
				(width 0.1)
				(type default)
			)
			(layer "F.Fab")
		)
		(fp_poly
			(pts
				(xy -2.2352 -0.298958) (xy -2.2352 -1.001014) (xy -1.533144 -0.649986)
			)
			(stroke
				(width 0)
				(type default)
			)
			(fill yes)
			(layer "F.Fab")
		)
		(pad "1" smd rect
			(at -0.94996 -0.649986 90)
			(size 0.4318 0.508)
			(layers "F.Cu" "F.Mask" "F.Paste")
			(net "GND")
		)
		(pad "2" smd rect
			(at -0.94996 0 90)
			(size 0.4318 0.508)
			(layers "F.Cu" "F.Mask" "F.Paste")
			(net "PWRGD_PVCCINFAON_CPU0")
		)
		(pad "3" smd rect
			(at -0.94996 0.649986 90)
			(size 0.4318 0.508)
			(layers "F.Cu" "F.Mask" "F.Paste")
			(net "LED_PWRGD_PVNN_MAIN_CPU0_D")
		)
		(pad "4" smd rect
			(at 0.94996 0.649986 90)
			(size 0.4318 0.508)
			(layers "F.Cu" "F.Mask" "F.Paste")
			(net "GND")
		)
		(pad "5" smd rect
			(at 0.94996 0 90)
			(size 0.4318 0.508)
			(layers "F.Cu" "F.Mask" "F.Paste")
			(net "PWRGD_PVNN_MAIN_CPU0")
		)
		(pad "6" smd rect
			(at 0.94996 -0.649986 90)
			(size 0.4318 0.508)
			(layers "F.Cu" "F.Mask" "F.Paste")
			(net "LED_PWRGD_PVCCINFAON_CPU0_D")
		)
	)
	(footprint ""
		(layer "F.Cu")
		(at 280.830528 -14.09827)
		(property "Reference" "R3193"
			(at 0 0 0)
			(layer "F.SilkS")
			(hide yes)
			(effects
				(font
					(size 1.27 1.27)
				)
			)
		)
		(property "Value" ""
			(at 0 0 0)
			(layer "F.Fab")
			(effects
				(font
					(size 1.27 1.27)
				)
			)
		)
		(duplicate_pad_numbers_are_jumpers no)
		(fp_line
			(start -0.7874 -0.4064)
			(end 0.7874 -0.4064)
			(stroke
				(width 0.1524)
				(type default)
			)
			(layer "F.SilkS")
		)
		(fp_line
			(start -0.7874 0.4064)
			(end -0.7874 -0.4064)
			(stroke
				(width 0.1524)
				(type default)
			)
			(layer "F.SilkS")
		)
		(fp_line
			(start 0.7874 -0.4064)
			(end 0.7874 0.4064)
			(stroke
				(width 0.1524)
				(type default)
			)
			(layer "F.SilkS")
		)
		(fp_line
			(start 0.7874 0.4064)
			(end -0.7874 0.4064)
			(stroke
				(width 0.1524)
				(type default)
			)
			(layer "F.SilkS")
		)
		(fp_line
			(start -0.67945 -0.305054)
			(end -0.12065 -0.305054)
			(stroke
				(width 0.1)
				(type default)
			)
			(layer "F.Fab")
		)
		(fp_line
			(start -0.67945 0.3048)
			(end -0.67945 -0.305054)
			(stroke
				(width 0.1)
				(type default)
			)
			(layer "F.Fab")
		)
		(fp_line
			(start -0.12065 -0.305054)
			(end -0.12065 -0.2794)
			(stroke
				(width 0.1)
				(type default)
			)
			(layer "F.Fab")
		)
		(fp_line
			(start -0.12065 -0.2794)
			(end 0.12065 -0.2794)
			(stroke
				(width 0.1)
				(type default)
			)
			(layer "F.Fab")
		)
		(fp_line
			(start -0.12065 0.2794)
			(end -0.12065 0.3048)
			(stroke
				(width 0.1)
				(type default)
			)
			(layer "F.Fab")
		)
		(fp_line
			(start -0.12065 0.3048)
			(end -0.67945 0.3048)
			(stroke
				(width 0.1)
				(type default)
			)
			(layer "F.Fab")
		)
		(fp_line
			(start 0.120396 0.2794)
			(end -0.12065 0.2794)
			(stroke
				(width 0.1)
				(type default)
			)
			(layer "F.Fab")
		)
		(fp_line
			(start 0.120396 0.3048)
			(end 0.120396 0.2794)
			(stroke
				(width 0.1)
				(type default)
			)
			(layer "F.Fab")
		)
		(fp_line
			(start 0.12065 -0.3048)
			(end 0.67945 -0.3048)
			(stroke
				(width 0.1)
				(type default)
			)
			(layer "F.Fab")
		)
		(fp_line
			(start 0.12065 -0.2794)
			(end 0.12065 -0.3048)
			(stroke
				(width 0.1)
				(type default)
			)
			(layer "F.Fab")
		)
		(fp_line
			(start 0.67945 -0.3048)
			(end 0.67945 0.3048)
			(stroke
				(width 0.1)
				(type default)
			)
			(layer "F.Fab")
		)
		(fp_line
			(start 0.67945 0.3048)
			(end 0.120396 0.3048)
			(stroke
				(width 0.1)
				(type default)
			)
			(layer "F.Fab")
		)
		(pad "1" smd circle
			(at -0.40005 0)
			(size 0 0)
			(layers "F.Cu" "F.Mask" "F.Paste")
			(net "IRQ_LVC3_V3_2_WAKE_BUF_N")
		)
		(pad "2" smd circle
			(at 0.40005 0)
			(size 0 0)
			(layers "F.Cu" "F.Mask" "F.Paste")
			(net "IRQ_LVC3_WAKE_N")
		)
	)
	(footprint ""
		(layer "F.Cu")
		(at 180.528468 -45.005498 180)
		(property "Reference" "C1098"
			(at 0 0 180)
			(layer "F.SilkS")
			(hide yes)
			(effects
				(font
					(size 1.27 1.27)
				)
			)
		)
		(property "Value" ""
			(at 0 0 180)
			(layer "F.Fab")
			(effects
				(font
					(size 1.27 1.27)
				)
			)
		)
		(duplicate_pad_numbers_are_jumpers no)
		(fp_line
			(start 0.299974 0.150114)
			(end -0.299974 0.150114)
			(stroke
				(width 0.1)
				(type default)
			)
			(layer "F.Fab")
		)
		(fp_line
			(start 0.299974 -0.150114)
			(end 0.299974 0.150114)
			(stroke
				(width 0.1)
				(type default)
			)
			(layer "F.Fab")
		)
		(fp_line
			(start -0.299974 0.150114)
			(end -0.299974 -0.150114)
			(stroke
				(width 0.1)
				(type default)
			)
			(layer "F.Fab")
		)
		(fp_line
			(start -0.299974 -0.150114)
			(end 0.299974 -0.150114)
			(stroke
				(width 0.1)
				(type default)
			)
			(layer "F.Fab")
		)
		(pad "1" smd rect
			(at -0.2667 0 180)
			(size 0.3048 0.381)
			(layers "F.Cu" "F.Mask" "F.Paste")
			(net "P3E_PCH_M2_TX_DP<3>")
		)
		(pad "2" smd rect
			(at 0.2667 0 180)
			(size 0.3048 0.381)
			(layers "F.Cu" "F.Mask" "F.Paste")
			(net "P3E_PCH_M2_TX_C_DP<3>")
		)
		(zone
			(layer "In1.Cu")
			(hatch none 0.5)
			(connect_pads
				(clearance 0)
			)
			(min_thickness 0.25)
			(keepout
				(tracks not_allowed)
				(vias allowed)
				(pads allowed)
				(copperpour not_allowed)
				(footprints allowed)
			)
			(placement
				(enabled no)
				(sheetname "")
			)
			(fill
				(thermal_gap 0.5)
				(thermal_bridge_width 0.5)
				(island_removal_mode 0)
			)
			(polygon
				(pts
					(arc
						(start 180.388768 -45.246798)
						(mid 180.44265 -45.22448)
						(end 180.464968 -45.170598)
					)
					(arc
						(start 180.464968 -44.840398)
						(mid 180.44265 -44.786516)
						(end 180.388768 -44.764198)
					)
					(arc
						(start 180.134768 -44.764198)
						(mid 180.080886 -44.786516)
						(end 180.058568 -44.840398)
					)
					(arc
						(start 180.058568 -45.170598)
						(mid 180.080886 -45.22448)
						(end 180.134768 -45.246798)
					)
				)
			)
		)
		(zone
			(layer "In1.Cu")
			(hatch none 0.5)
			(connect_pads
				(clearance 0)
			)
			(min_thickness 0.25)
			(keepout
				(tracks not_allowed)
				(vias allowed)
				(pads allowed)
				(copperpour not_allowed)
				(footprints allowed)
			)
			(placement
				(enabled no)
				(sheetname "")
			)
			(fill
				(thermal_gap 0.5)
				(thermal_bridge_width 0.5)
				(island_removal_mode 0)
			)
			(polygon
				(pts
					(arc
						(start 180.922168 -45.246798)
						(mid 180.97605 -45.22448)
						(end 180.998368 -45.170598)
					)
					(arc
						(start 180.998368 -44.840398)
						(mid 180.97605 -44.786516)
						(end 180.922168 -44.764198)
					)
					(arc
						(start 180.668168 -44.764198)
						(mid 180.614286 -44.786516)
						(end 180.591968 -44.840398)
					)
					(arc
						(start 180.591968 -45.170598)
						(mid 180.614286 -45.22448)
						(end 180.668168 -45.246798)
					)
				)
			)
		)
	)
	(footprint ""
		(layer "F.Cu")
		(at 289.545268 -367.378996 90)
		(property "Reference" "PR1783"
			(at 0 0 90)
			(layer "F.SilkS")
			(hide yes)
			(effects
				(font
					(size 1.27 1.27)
				)
			)
		)
		(property "Value" ""
			(at 0 0 90)
			(layer "F.Fab")
			(effects
				(font
					(size 1.27 1.27)
				)
			)
		)
		(duplicate_pad_numbers_are_jumpers no)
		(fp_line
			(start 0.7874 -0.4064)
			(end 0.7874 0.4064)
			(stroke
				(width 0.1524)
				(type default)
			)
			(layer "F.SilkS")
		)
		(fp_line
			(start -0.7874 -0.4064)
			(end 0.7874 -0.4064)
			(stroke
				(width 0.1524)
				(type default)
			)
			(layer "F.SilkS")
		)
		(fp_line
			(start 0.7874 0.4064)
			(end -0.7874 0.4064)
			(stroke
				(width 0.1524)
				(type default)
			)
			(layer "F.SilkS")
		)
		(fp_line
			(start -0.7874 0.4064)
			(end -0.7874 -0.4064)
			(stroke
				(width 0.1524)
				(type default)
			)
			(layer "F.SilkS")
		)
		(fp_line
			(start -0.12065 -0.305054)
			(end -0.12065 -0.2794)
			(stroke
				(width 0.1)
				(type default)
			)
			(layer "F.Fab")
		)
		(fp_line
			(start -0.67945 -0.305054)
			(end -0.12065 -0.305054)
			(stroke
				(width 0.1)
				(type default)
			)
			(layer "F.Fab")
		)
		(fp_line
			(start 0.67945 -0.3048)
			(end 0.67945 0.3048)
			(stroke
				(width 0.1)
				(type default)
			)
			(layer "F.Fab")
		)
		(fp_line
			(start 0.12065 -0.3048)
			(end 0.67945 -0.3048)
			(stroke
				(width 0.1)
				(type default)
			)
			(layer "F.Fab")
		)
		(fp_line
			(start 0.12065 -0.2794)
			(end 0.12065 -0.3048)
			(stroke
				(width 0.1)
				(type default)
			)
			(layer "F.Fab")
		)
		(fp_line
			(start -0.12065 -0.2794)
			(end 0.12065 -0.2794)
			(stroke
				(width 0.1)
				(type default)
			)
			(layer "F.Fab")
		)
		(fp_line
			(start 0.120396 0.2794)
			(end -0.12065 0.2794)
			(stroke
				(width 0.1)
				(type default)
			)
			(layer "F.Fab")
		)
		(fp_line
			(start -0.12065 0.2794)
			(end -0.12065 0.3048)
			(stroke
				(width 0.1)
				(type default)
			)
			(layer "F.Fab")
		)
		(fp_line
			(start 0.67945 0.3048)
			(end 0.120396 0.3048)
			(stroke
				(width 0.1)
				(type default)
			)
			(layer "F.Fab")
		)
		(fp_line
			(start 0.120396 0.3048)
			(end 0.120396 0.2794)
			(stroke
				(width 0.1)
				(type default)
			)
			(layer "F.Fab")
		)
		(fp_line
			(start -0.12065 0.3048)
			(end -0.67945 0.3048)
			(stroke
				(width 0.1)
				(type default)
			)
			(layer "F.Fab")
		)
		(fp_line
			(start -0.67945 0.3048)
			(end -0.67945 -0.305054)
			(stroke
				(width 0.1)
				(type default)
			)
			(layer "F.Fab")
		)
		(pad "1" smd circle
			(at -0.40005 0 90)
			(size 0 0)
			(layers "F.Cu" "F.Mask" "F.Paste")
			(net "SW_PVCCFA_EHV_FIVRA_CPU0_BOOT4")
		)
		(pad "2" smd circle
			(at 0.40005 0 90)
			(size 0 0)
			(layers "F.Cu" "F.Mask" "F.Paste")
			(net "SW_PVCCFA_EHV_FIVRA_CPU0_BOOT4_")
		)
	)
)
